FILE_TYPE = CONNECTIVITY;
{Allegro Design Entry HDL 16.6-p007 (v16-6-112F) 10/10/2012}
"PAGE_NUMBER" = 92;
0"NC";
1"PVCCIO_CPU1\g";
2"P3V3\g";
3"P3V3\g";
4"PVCCIO_CPU0\g";
5"PVCCIO_CPU0\g";
6"GND\g";
7"GND\g";
8"GND\g";
9"P3V3\g";
10"GND\g";
11"GND\g";
12"GND\g";
13"P3V3\g";
14"PVCCIO_CPU0\g";
15"GND\g";
16"GND\g";
17"PVCCIO_CPU0\g";
18"GND\g";
19"PVCCIO_CPU0\g";
20"PVCCIO_CPU0\g";
21"PWRGD_CPUPWRGD_R1";
22"H_CPU1_THERMTRIP_G_N";
23"H_CPU_CATERR_G_N";
24"H_CPU_ERR2_GTL_N";
25"P0V7_GTL2104_VREF_0"VOLTAGE"+0.7 V";
26"FM_CPU_CATERR_LVT3_R2_N";
27"H_CPU0_CATERR_G_N";
28"H_CPU_ERR2_G_R_N";
29"H_CPU1_ERR2_G_N";
30"H_CPU0_ERR2_G_N";
31"H_CPU1_FIVR_FAULT_G";
32"H_CPU0_MSMI_G_N";
33"H_CPU1_MSMI_G_N";
34"H_CPU1_CATERR_G_N";
35"H_CPU_MSMI_G_N";
36"H_CPU0_FIVR_FAULT_G";
37"PD_GTL2104_DIR_0";
38"FM_CPU0_THERMTRIP_LVT3_R_N";
39"FM_CPU1_THERMTRIP_LVT3_R_N";
40"FM_CPU_ERR2_LVT3_R_N";
41"FM_CPU_MSMI_LVT3_R_N";
42"FM_CPU0_FIVR_FAULT_R_LVT3";
43"FM_CPU0_THERMTRIP_LVT3_N";
44"FM_CPU_ERR2_LVT3_N";
45"FM_CPU_MSMI_LVT3_N";
46"FM_CPU0_FIVR_FAULT_LVT3";
47"FM_CPU_CATERR_LVT3_N";
48"FM_CPU1_FIVR_FAULT_LVT3";
49"FM_CPU1_THERMTRIP_LVT3_N";
50"PWRGD_CPUPWRGD_GTL";
51"H_CPU0_THERMTRIP_G_N";
52"PD_GTL2104_DIR_1";
53"FM_CPU1_FIVR_FAULT_R_LVT3";
54"PWRGD_CPUPWRGD";
55"P0V7_GTL2104_VREF_1"VOLTAGE"+0.7 V";
%"GTL2014"
"1","(-1825,4250)","2","mstr_digital","I1";
;
CDS_SEC"1"
LOCATION"U3P2"
MATERIAL"IC"
PART_NUMBER"D66151-001"
PACK_TYPE"SM"
SEC_TYPE"SM"
BOM_COST"PROC_SIDEBAND"
CDS_LIB"mstr_digital"
SEC"1"
CDS_LOCATION"U3P2"
ROOM"PROC_SIDEBAND";
"A0"
$PN"13"21;
"A1"
$PN"12"53;
"A3"
$PN"9"39;
"A2"
$PN"10"26;
"B2"
$PN"5"23;
"B3"
$PN"6"22;
"B0"
$PN"2"50;
"B1"
$PN"3"31;
"GND<1>"
$PN"8"6;
"GND<2>"
$PN"11"6;
"GND<0>"
$PN"7"6;
"VCC"
$PN"14"9;
"VREF"
$PN"4"55;
"DIR"
$PN"1"52;
%"PVCCIO_CPU1"
"1","(-2900,4750)","0","mstr_symbols","I10";
;
VOLTAGE"1.1V"
CDS_LIB"mstr_symbols"
BODY_TYPE"PLUMBING"
HDL_POWER"PVCCIO_CPU1";
"G\NAC"1;
%"RES"
"2","(-4350,4600)","0","mstr_discrete","I100";
;
CDS_SEC"1"
LOCATION"R7P18"
PART_NUMBER"G21796-009"
VALUE"150.0"
TOLERANCE"1%"
PACK_TYPE"0402"
MATERIAL"CHIP"
WATTAGE"1/16W"
CDS_LIB"mstr_discrete"
BOM_COST"PROC"
SEC_TYPE"0402"
SEC"1"
CDS_LOCATION"R7P18"
ROOM"PROC_SIDEBAND";
"A"
$PN"1"20;
"B"
$PN"2"34;
%"RES"
"2","(-4450,4600)","2","mstr_discrete","I101";
;
CDS_SEC"1"
LOCATION"R4R2"
PART_NUMBER"G21796-009"
VALUE"150.0"
TOLERANCE"1%"
PACK_TYPE"0402"
MATERIAL"CHIP"
WATTAGE"1/16W"
SEC_TYPE"0402"
CDS_LIB"mstr_discrete"
BOM_COST"PROC"
SEC"1"
CDS_LOCATION"R4R2"
ROOM"PROC_SIDEBAND";
"A"
$PN"1"20;
"B"
$PN"2"27;
%"P3V3"
"1","(100,5550)","0","mstr_symbols","I104";
;
CDS_LIB"mstr_symbols"
SIZE"1B"
VOLTAGE"3.3V"
BODY_TYPE"PLUMBING"
HDL_POWER"P3V3";
"G\NAC"2;
%"P3V3"
"1","(350,3250)","0","mstr_symbols","I105";
;
VOLTAGE"3.3V"
CDS_LIB"mstr_symbols"
SIZE"1B"
BODY_TYPE"PLUMBING"
HDL_POWER"P3V3";
"G\NAC"3;
%"RES"
"2","(-100,3050)","0","mstr_discrete","I106";
;
CDS_SEC"1"
PART_NUMBER"G21796-047"
MATERIAL"EMPTY"
WATTAGE"1/16W"
TOLERANCE"1%"
VALUE"49.9"
LOCATION"R7W4"
PACK_TYPE"0402"
SEC_TYPE"0402"
SEC"1"
ROOM"SB"
CDS_LIB"mstr_discrete"
CDS_LOCATION"R7W4";
"A"
$PN"1"4;
"B"
$PN"2"25;
%"PVCCIO_CPU0"
"1","(-100,3250)","0","mstr_symbols","I107";
;
CDS_LIB"mstr_symbols"
VOLTAGE"1.1V"
BODY_TYPE"PLUMBING"
HDL_POWER"PVCCIO_CPU0";
"G\NAC"4;
%"RES"
"2","(-400,5350)","0","mstr_discrete","I108";
;
CDS_SEC"1"
PART_NUMBER"G21796-047"
MATERIAL"EMPTY"
WATTAGE"1/16W"
TOLERANCE"1%"
VALUE"49.9"
LOCATION"R3W10"
PACK_TYPE"0402"
CDS_LOCATION"R3W10"
SEC_TYPE"0402"
SEC"1"
ROOM"SB"
CDS_LIB"mstr_discrete";
"A"
$PN"1"5;
"B"
$PN"2"55;
%"PVCCIO_CPU0"
"1","(-400,5550)","0","mstr_symbols","I109";
;
VOLTAGE"1.1V"
CDS_LIB"mstr_symbols"
BODY_TYPE"PLUMBING"
HDL_POWER"PVCCIO_CPU0";
"G\NAC"5;
%"374R2F-1-GP"
"1","(100,5325)","0","w_hdl","I110";
;
CDS_SEC"1"
$SEC"1"
CDS_LOCATION"R3P45"
TOLERANCE"1%"
PACK_SIZE"0402"
RATED"1/16W"
ATTRIBUTE"374 OHM"
VALUE"374R2F-1-GP"
LOCATION"R3P45"
PACK_TYPE"SMD-RG"
PART_NUMBER"64.37405.6DL"
CDS_LIB"w_hdl"
CDS_LMAN_SYM_OUTLINE"-50,75,50,-75";
"2"
$PN"2"55;
"1"
$PN"1"2;
%"374R2F-1-GP"
"1","(350,3025)","0","w_hdl","I111";
;
CDS_SEC"1"
$SEC"1"
CDS_LOCATION"R7D33"
LOCATION"R7D33"
RATED"1/16W"
TOLERANCE"1%"
ATTRIBUTE"374 OHM"
VALUE"374R2F-1-GP"
PACK_SIZE"0402"
PACK_TYPE"SMD-RG"
PART_NUMBER"64.37405.6DL"
CDS_LIB"w_hdl"
CDS_LMAN_SYM_OUTLINE"-50,75,50,-75";
"2"
$PN"2"25;
"1"
$PN"1"3;
%"RES"
"1","(-125,3750)","0","mstr_discrete","I12";
;
CDS_SEC"1"
LOCATION"R3P46"
VALUE"33.2"
TOLERANCE"1%"
PART_NUMBER"G21796-074"
MATERIAL"CHIP"
PACK_TYPE"0402"
WATTAGE"1/16W"
SEC_TYPE"0402"
BOM_COST"PROC_SIDEBAND"
CDS_LIB"mstr_discrete"
SEC"1"
CDS_LOCATION"R3P46"
ROOM"PROC_SIDEBAND";
"B"
$PN"2"48;
"A"
$PN"1"53;
%"RES"
"1","(-125,4000)","0","mstr_discrete","I13";
;
CDS_SEC"1"
MATERIAL"CHIP"
VALUE"33.2"
TOLERANCE"1%"
LOCATION"R3P43"
WATTAGE"1/16W"
PART_NUMBER"G21796-074"
PACK_TYPE"0402"
SEC_TYPE"0402"
BOM_COST"PROC_SIDEBAND"
CDS_LIB"mstr_discrete"
SEC"1"
CDS_LOCATION"R3P43"
ROOM"PROC_SIDEBAND";
"B"
$PN"2"47;
"A"
$PN"1"26;
%"RES"
"1","(-125,4250)","0","mstr_discrete","I14";
;
CDS_SEC"1"
PACK_TYPE"0402"
MATERIAL"CHIP"
WATTAGE"1/16W"
TOLERANCE"1%"
VALUE"33.2"
LOCATION"R3P42"
PART_NUMBER"G21796-074"
SEC_TYPE"0402"
BOM_COST"PROC_SIDEBAND"
CDS_LIB"mstr_discrete"
SEC"1"
CDS_LOCATION"R3P42"
ROOM"PROC_SIDEBAND";
"B"
$PN"2"49;
"A"
$PN"1"39;
%"RES"
"2","(-2850,2325)","0","mstr_discrete","I19";
;
CDS_SEC"1"
WATTAGE"1/16W"
LOCATION"R7E2"
PACK_TYPE"0402"
MATERIAL"CHIP"
PART_NUMBER"G21796-267"
VALUE"75"
TOLERANCE"1.0%"
SEC_TYPE"0402"
CDS_LIB"mstr_discrete"
BOM_COST"PROC_SIDEBAND"
SEC"1"
CDS_LOCATION"R7E2"
ROOM"PROC_SIDEBAND";
"A"
$PN"1"17;
"B"
$PN"2"51;
%"GND"
"1","(-2550,3725)","0","mstr_symbols","I2";
;
VOLTAGE"0"
SIZE"1B"
CDS_LIB"mstr_symbols"
BODY_TYPE"PLUMBING"
HDL_POWER"GND";
"A\NAC"6;
%"RES"
"1","(-125,2050)","0","mstr_discrete","I24";
;
CDS_SEC"1"
PACK_TYPE"0402"
WATTAGE"1/16W"
PART_NUMBER"G21796-074"
VALUE"33.2"
TOLERANCE"1%"
MATERIAL"CHIP"
LOCATION"R7D34"
SEC_TYPE"0402"
BOM_COST"PROC_SIDEBAND"
CDS_LIB"mstr_discrete"
SEC"1"
CDS_LOCATION"R7D34"
ROOM"PROC_SIDEBAND";
"B"
$PN"2"43;
"A"
$PN"1"38;
%"RES"
"1","(-100,1800)","0","mstr_discrete","I29";
;
CDS_SEC"1"
PART_NUMBER"G21796-074"
VALUE"33.2"
MATERIAL"CHIP"
LOCATION"R7D31"
TOLERANCE"1%"
PACK_TYPE"0402"
WATTAGE"1/16W"
SEC_TYPE"0402"
BOM_COST"PROC_SIDEBAND"
CDS_LIB"mstr_discrete"
SEC"1"
CDS_LOCATION"R7D31"
ROOM"PROC_SIDEBAND";
"B"
$PN"2"44;
"A"
$PN"1"40;
%"RES"
"1","(-100,1550)","0","mstr_discrete","I30";
;
CDS_SEC"1"
PART_NUMBER"G21796-074"
LOCATION"R7D29"
PACK_TYPE"0402"
VALUE"33.2"
TOLERANCE"1%"
MATERIAL"CHIP"
WATTAGE"1/16W"
BOM_COST"PROC_SIDEBAND"
CDS_LIB"mstr_discrete"
SEC_TYPE"0402"
SEC"1"
CDS_LOCATION"R7D29"
ROOM"PROC_SIDEBAND";
"B"
$PN"2"46;
"A"
$PN"1"42;
%"GTL2014"
"1","(-1750,2050)","2","mstr_digital","I32";
;
CDS_SEC"1"
MATERIAL"IC"
PART_NUMBER"D66151-001"
LOCATION"U7D2"
PACK_TYPE"SM"
CDS_LIB"mstr_digital"
BOM_COST"PROC_SIDEBAND"
SEC_TYPE"SM"
SEC"1"
CDS_LOCATION"U7D2"
ROOM"PROC_SIDEBAND";
"A0"
$PN"13"41;
"A1"
$PN"12"42;
"A3"
$PN"9"38;
"A2"
$PN"10"40;
"B2"
$PN"5"24;
"B3"
$PN"6"51;
"B0"
$PN"2"35;
"B1"
$PN"3"36;
"GND<1>"
$PN"8"7;
"GND<2>"
$PN"11"7;
"GND<0>"
$PN"7"7;
"VCC"
$PN"14"13;
"VREF"
$PN"4"25;
"DIR"
$PN"1"37;
%"GND"
"1","(-2475,1525)","0","mstr_symbols","I33";
;
VOLTAGE"0"
CDS_LIB"mstr_symbols"
SIZE"1B"
BODY_TYPE"PLUMBING"
HDL_POWER"GND";
"A\NAC"7;
%"CAP_A"
"1","(-400,4800)","0","dev_discrete","I37";
;
VOLTAGE"16V"
PACK_TYPE"0402V"
PART_NUMBER"A36096-030"
TOLERANCE"10%"
MATERIAL"X7R"
VALUE"0.1UF"
LOCATION"C3P49"
ROOM"PROC_SIDEBAND"
CDS_LOCATION"C3P49"
BOM_COST"PROC_SIDEBAND"
CDS_LIB"dev_discrete"
CDS_SEC"1"
SEC_TYPE"0402V"
SEC"1";
"B"
$PN"2"8;
"A"
$PN"1"55;
%"RES"
"2","(100,4800)","0","mstr_discrete","I38";
;
CDS_SEC"1"
PART_NUMBER"G21796-017"
PACK_TYPE"0402"
TOLERANCE"1%"
VALUE"100.0"
WATTAGE"1/16W"
MATERIAL"CHIP"
LOCATION"R3P49"
ROOM"PROC_SIDEBAND"
CDS_LOCATION"R3P49"
SEC"1"
BOM_COST"PROC_SIDEBAND"
CDS_LIB"mstr_discrete"
SEC_TYPE"0402";
"A"
$PN"1"55;
"B"
$PN"2"8;
%"GND"
"1","(100,4450)","0","mstr_symbols","I41";
;
SIZE"1B"
CDS_LIB"mstr_symbols"
VOLTAGE"0"
BODY_TYPE"PLUMBING"
HDL_POWER"GND";
"A\NAC"8;
%"P3V3"
"1","(-1175,4950)","0","mstr_symbols","I42";
;
CDS_LIB"mstr_symbols"
SIZE"1B"
VOLTAGE"3.3V"
BODY_TYPE"PLUMBING"
HDL_POWER"P3V3";
"G\NAC"9;
%"RES"
"1","(-675,4400)","0","mstr_discrete","I46";
;
CDS_SEC"1"
VALUE"1.00K"
PACK_TYPE"0402"
PART_NUMBER"G21796-026"
LOCATION"R3R1"
WATTAGE"1/16W"
TOLERANCE"1%"
MATERIAL"CHIP"
SEC_TYPE"0402"
CDS_LIB"mstr_discrete"
BOM_COST"PROC_SIDEBAND"
SEC"1"
CDS_LOCATION"R3R1"
ROOM"PROC_SIDEBAND";
"B"
$PN"2"10;
"A"
$PN"1"52;
%"GND"
"1","(-300,4325)","0","mstr_symbols","I47";
;
VOLTAGE"0"
CDS_LIB"mstr_symbols"
SIZE"1B"
BODY_TYPE"PLUMBING"
HDL_POWER"GND";
"A\NAC"10;
%"RES"
"2","(350,2550)","0","mstr_discrete","I48";
;
CDS_SEC"1"
VALUE"100.0"
TOLERANCE"1%"
LOCATION"R7D32"
PACK_TYPE"0402"
MATERIAL"CHIP"
WATTAGE"1/16W"
PART_NUMBER"G21796-017"
ROOM"PROC_SIDEBAND"
CDS_LOCATION"R7D32"
SEC"1"
SEC_TYPE"0402"
BOM_COST"PROC_SIDEBAND"
CDS_LIB"mstr_discrete";
"A"
$PN"1"25;
"B"
$PN"2"11;
%"GND"
"1","(350,2200)","0","mstr_symbols","I49";
;
CDS_LIB"mstr_symbols"
SIZE"1B"
VOLTAGE"0"
BODY_TYPE"PLUMBING"
HDL_POWER"GND";
"A\NAC"11;
%"CAP_A"
"1","(-100,2550)","0","dev_discrete","I52";
;
TOLERANCE"10%"
PACK_TYPE"0402V"
MATERIAL"X7R"
VOLTAGE"16V"
PART_NUMBER"A36096-030"
VALUE"0.1UF"
LOCATION"C7D5"
ROOM"PROC_SIDEBAND"
CDS_LOCATION"C7D5"
BOM_COST"PROC_SIDEBAND"
CDS_LIB"dev_discrete"
CDS_SEC"1"
SEC_TYPE"0402V"
SEC"1";
"B"
$PN"2"11;
"A"
$PN"1"25;
%"GND"
"1","(-225,2125)","0","mstr_symbols","I53";
;
VOLTAGE"0"
CDS_LIB"mstr_symbols"
SIZE"1B"
BODY_TYPE"PLUMBING"
HDL_POWER"GND";
"A\NAC"12;
%"RES"
"1","(-600,2200)","0","mstr_discrete","I54";
;
CDS_SEC"1"
LOCATION"R7D26"
TOLERANCE"1%"
PART_NUMBER"G21796-026"
VALUE"1.00K"
PACK_TYPE"0402"
WATTAGE"1/16W"
MATERIAL"CHIP"
BOM_COST"PROC_SIDEBAND"
CDS_LIB"mstr_discrete"
SEC_TYPE"0402"
SEC"1"
CDS_LOCATION"R7D26"
ROOM"PROC_SIDEBAND";
"B"
$PN"2"12;
"A"
$PN"1"37;
%"P3V3"
"1","(-1050,2750)","0","mstr_symbols","I58";
;
VOLTAGE"3.3V"
CDS_LIB"mstr_symbols"
SIZE"1B"
BODY_TYPE"PLUMBING"
HDL_POWER"P3V3";
"G\NAC"13;
%"RES"
"1","(-125,3550)","0","mstr_discrete","I61";
;
CDS_SEC"1"
MATERIAL"CHIP"
WATTAGE"1/16W"
TOLERANCE"1%"
VALUE"33.2"
LOCATION"R3R3"
PACK_TYPE"0402"
PART_NUMBER"G21796-074"
SEC_TYPE"0402"
BOM_COST"PROC_SIDEBAND"
CDS_LIB"mstr_discrete"
SEC"1"
CDS_LOCATION"R3R3"
ROOM"PROC_SIDEBAND";
"B"
$PN"2"54;
"A"
$PN"1"21;
%"RES"
"2","(-4600,1825)","2","mstr_discrete","I64";
;
CDS_SEC"1"
LOCATION"R6D9"
PART_NUMBER"G21796-009"
TOLERANCE"1%"
PACK_TYPE"0402"
MATERIAL"CHIP"
WATTAGE"1/16W"
VALUE"150.0"
SEC_TYPE"0402"
BOM_COST"PROC_SIDEBAND"
CDS_LIB"mstr_discrete"
SEC"1"
CDS_LOCATION"R6D9"
ROOM"PROC_SIDEBAND";
"A"
$PN"1"14;
"B"
$PN"2"32;
%"RES"
"2","(-4275,1800)","0","mstr_discrete","I65";
;
CDS_SEC"1"
LOCATION"R7P27"
PART_NUMBER"G21796-009"
VALUE"150.0"
PACK_TYPE"0402"
MATERIAL"CHIP"
WATTAGE"1/16W"
TOLERANCE"1%"
CDS_LIB"mstr_discrete"
BOM_COST"PROC_SIDEBAND"
SEC_TYPE"0402"
SEC"1"
CDS_LOCATION"R7P27"
ROOM"PROC_SIDEBAND";
"A"
$PN"1"14;
"B"
$PN"2"33;
%"PVCCIO_CPU0"
"1","(-4600,2050)","0","mstr_symbols","I66";
;
VOLTAGE"1.1V"
CDS_LIB"mstr_symbols"
BODY_TYPE"PLUMBING"
HDL_POWER"PVCCIO_CPU0";
"G\NAC"14;
%"RES"
"1","(-3725,1275)","0","mstr_discrete","I67";
;
CDS_SEC"1"
LOCATION"R7D28"
PART_NUMBER"G21497-005"
VALUE"0.0"
TOLERANCE"5%"
PACK_TYPE"0402"
MATERIAL"CHIP"
WATTAGE"1/16W"
BOM_COST"PROC_SIDEBAND"
CDS_LIB"mstr_discrete"
SEC_TYPE"0402"
SEC"1"
CDS_LOCATION"R7D28"
ROOM"PROC_SIDEBAND";
"B"
$PN"2"35;
"A"
$PN"1"33;
%"RES"
"1","(-3775,1550)","0","mstr_discrete","I68";
;
CDS_SEC"1"
LOCATION"R7D27"
PART_NUMBER"G21497-005"
VALUE"0.0"
TOLERANCE"5%"
PACK_TYPE"0402"
MATERIAL"CHIP"
WATTAGE"1/16W"
CDS_LIB"mstr_discrete"
SEC_TYPE"0402"
BOM_COST"PROC_SIDEBAND"
SEC"1"
CDS_LOCATION"R7D27"
ROOM"PROC_SIDEBAND";
"B"
$PN"2"35;
"A"
$PN"1"32;
%"RES"
"1","(-100,1250)","0","mstr_discrete","I70";
;
CDS_SEC"1"
LOCATION"R7D25"
PART_NUMBER"G21796-074"
VALUE"33.2"
TOLERANCE"1%"
PACK_TYPE"0402"
MATERIAL"CHIP"
WATTAGE"1/16W"
SEC_TYPE"0402"
BOM_COST"PROC_SIDEBAND"
CDS_LIB"mstr_discrete"
SEC"1"
CDS_LOCATION"R7D25"
ROOM"PROC_SIDEBAND";
"B"
$PN"2"45;
"A"
$PN"1"41;
%"RES"
"2","(-2925,3900)","0","mstr_discrete","I75";
;
CDS_SEC"1"
LOCATION"R3R2"
PART_NUMBER"G21796-026"
VALUE"1.00K"
TOLERANCE"1%"
PACK_TYPE"0402"
MATERIAL"CHIP"
WATTAGE"1/16W"
ROOM"PROC_SIDEBAND"
SEC_TYPE"0402"
SEC"1"
CDS_LIB"mstr_discrete"
CDS_LOCATION"R3R2";
"A"
$PN"1"31;
"B"
$PN"2"15;
%"GND"
"1","(-2925,3650)","0","mstr_symbols","I76";
;
VOLTAGE"0"
SIZE"1B"
CDS_LIB"mstr_symbols"
BODY_TYPE"PLUMBING"
HDL_POWER"GND";
"A\NAC"15;
%"CAP"
"1","(-900,2525)","0","mstr_discrete","I79";
;
CDS_SEC"1"
VALUE"1.0UF"
VOLTAGE"16V"
TOLERANCE"10%"
LOCATION"C7D4"
PACK_TYPE"0402"
PART_NUMBER"D97712-011"
MATERIAL"X6S"
CDS_LIB"mstr_discrete"
SEC_TYPE"0402"
BOM_COST"PROC"
SEC"1"
CDS_LOCATION"C7D4"
ROOM"PROC_SIDEBAND";
"A"
$PN"1"13;
"B"
$PN"2"16;
%"GND"
"1","(-900,2350)","0","mstr_symbols","I80";
;
VOLTAGE"0"
CDS_LIB"mstr_symbols"
SIZE"1B"
BODY_TYPE"PLUMBING"
HDL_POWER"GND";
"A\NAC"16;
%"PVCCIO_CPU0"
"1","(-2850,2700)","0","mstr_symbols","I82";
;
CDS_LIB"mstr_symbols"
VOLTAGE"1.1V"
BODY_TYPE"PLUMBING"
HDL_POWER"PVCCIO_CPU0";
"G\NAC"17;
%"CAP"
"1","(-1025,4725)","0","mstr_discrete","I84";
;
CDS_SEC"1"
PART_NUMBER"D97712-011"
MATERIAL"X6S"
TOLERANCE"10%"
VOLTAGE"16V"
VALUE"1.0UF"
LOCATION"C3P50"
PACK_TYPE"0402"
SEC_TYPE"0402"
CDS_LIB"mstr_discrete"
BOM_COST"PROC"
SEC"1"
CDS_LOCATION"C3P50"
ROOM"PROC_SIDEBAND";
"A"
$PN"1"9;
"B"
$PN"2"18;
%"GND"
"1","(-1025,4550)","0","mstr_symbols","I85";
;
VOLTAGE"0"
SIZE"1B"
CDS_LIB"mstr_symbols"
BODY_TYPE"PLUMBING"
HDL_POWER"GND";
"A\NAC"18;
%"RES"
"2","(-2900,4525)","0","mstr_discrete","I9";
;
CDS_SEC"1"
PACK_TYPE"0402"
LOCATION"R3P41"
TOLERANCE"1.0%"
PART_NUMBER"G21796-267"
MATERIAL"CHIP"
WATTAGE"1/16W"
VALUE"75"
CDS_LIB"mstr_discrete"
BOM_COST"PROC_SIDEBAND"
SEC_TYPE"0402"
SEC"1"
CDS_LOCATION"R3P41"
ROOM"PROC_SIDEBAND";
"A"
$PN"1"1;
"B"
$PN"2"22;
%"RES"
"1","(-4725,2550)","0","mstr_discrete","I92";
;
MATERIAL"CHIP"
PACK_TYPE"0402"
PART_NUMBER"G21497-005"
WATTAGE"1/16W"
TOLERANCE"5%"
VALUE"0.0"
LOCATION"R2T44"
ROOM"PROC_SIDEBAND"
CDS_LOCATION"R2T44"
$SEC"1"
CDS_SEC"1"
CDS_LIB"mstr_discrete"
BOM_COST"PROC";
"B"
$PN"2"28;
"A"
$PN"1"29;
%"RES"
"1","(-4750,2800)","0","mstr_discrete","I93";
;
WATTAGE"1/16W"
MATERIAL"CHIP"
TOLERANCE"5%"
VALUE"0.0"
LOCATION"R2T40"
PART_NUMBER"G21497-005"
PACK_TYPE"0402"
ROOM"PROC_SIDEBAND"
CDS_LOCATION"R2T40"
$SEC"1"
CDS_SEC"1"
CDS_LIB"mstr_discrete"
BOM_COST"PROC";
"B"
$PN"2"28;
"A"
$PN"1"30;
%"RES"
"2","(-4000,2950)","0","mstr_discrete","I94";
;
TOLERANCE"1%"
PACK_TYPE"0402"
LOCATION"R2T37"
VALUE"200.0"
PART_NUMBER"G21796-004"
MATERIAL"CHIP"
WATTAGE"1/16W"
CDS_LIB"mstr_discrete"
BOM_COST"PROC"
CDS_SEC"1"
$SEC"1"
CDS_LOCATION"R2T37"
ROOM"PROC_SIDEBAND";
"A"
$PN"1"19;
"B"
$PN"2"28;
%"PVCCIO_CPU0"
"1","(-4000,3175)","0","mstr_symbols","I95";
;
VOLTAGE"1.1V"
CDS_LIB"mstr_symbols"
BODY_TYPE"PLUMBING"
HDL_POWER"PVCCIO_CPU0";
"G\NAC"19;
%"RES"
"1","(-3675,2675)","0","mstr_discrete","I96";
;
VALUE"75"
TOLERANCE"1.0%"
MATERIAL"CHIP"
WATTAGE"1/16W"
PACK_TYPE"0402"
PART_NUMBER"G21796-267"
LOCATION"R2T43"
BOM_COST"PROC"
CDS_LIB"mstr_discrete"
CDS_SEC"1"
$SEC"1"
CDS_LOCATION"R2T43"
ROOM"PROC_SIDEBAND";
"B"
$PN"2"24;
"A"
$PN"1"28;
%"RES"
"1","(-3775,4350)","0","mstr_discrete","I97";
;
CDS_SEC"1"
CDS_LOCATION"R3P59"
LOCATION"R3P59"
PART_NUMBER"G21497-005"
VALUE"0.0"
TOLERANCE"5%"
PACK_TYPE"0402"
MATERIAL"CHIP"
WATTAGE"1/16W"
CDS_LIB"mstr_discrete"
SEC_TYPE"0402"
BOM_COST"PROC"
SEC"1"
ROOM"PROC_SIDEBAND";
"B"
$PN"2"23;
"A"
$PN"1"27;
%"RES"
"1","(-3750,4100)","0","mstr_discrete","I98";
;
CDS_SEC"1"
CDS_LOCATION"R3P58"
LOCATION"R3P58"
PART_NUMBER"G21497-005"
VALUE"0.0"
TOLERANCE"5%"
PACK_TYPE"0402"
MATERIAL"CHIP"
WATTAGE"1/16W"
BOM_COST"PROC"
SEC_TYPE"0402"
CDS_LIB"mstr_discrete"
SEC"1"
ROOM"PROC_SIDEBAND";
"B"
$PN"2"23;
"A"
$PN"1"34;
%"PVCCIO_CPU0"
"1","(-4450,4850)","0","mstr_symbols","I99";
;
VOLTAGE"1.1V"
CDS_LIB"mstr_symbols"
BODY_TYPE"PLUMBING"
HDL_POWER"PVCCIO_CPU0";
"G\NAC"20;
END.
